# T6G (Grand Teton) — schematic netlist excerpt (pin names and nets, part order shuffled) for the footprints in the layout excerpt that follows; sources: Cadence DE-HDL packaged netlist, KiCad conversion of 04192023_DAF0TMB3IC0_F0TG_MB_C_brd_V02_OCP.brd

U8009  LM4040AIM3X25NOPB  LM4040AIM3X-2.5/NOPB IC  pkg SOT23_123_2-92X1-3  page 268
  \1+\  = UV_P2V5_COMP
  \2-\  = GND
  \3\  = NC

R1308  Q_RES  4.7K 1% CHIP  pkg 0402LF  page 357 : A = GND ; B = INA230_8_A0
C6087  Q_CAP  0.1UF 25V 10% X7R  pkg 0402  page 271 : A = P3V3_AUX ; B = GND

(kicad_pcb
	(version 20260206)
	(generator "pcbnew")
	(generator_version "10.0")
	(general
		(thickness 1.6)
		(legacy_teardrops no)
	)
	(paper "A4")
	(title_block
		(title "04192023_DAF0TMB3IC0_F0TG_MB_C_brd_V02_OCP.brd")
		(comment 1 "Grand Teton / footprints 2438-2440 of 8354")
	)
	(layers
		(0 "F.Cu" signal "TOP")
		(4 "In1.Cu" signal "GND")
		(6 "In2.Cu" signal "IN1")
		(8 "In3.Cu" signal "GND1")
		(10 "In4.Cu" signal "IN2")
		(12 "In5.Cu" signal "GND2")
		(14 "In6.Cu" signal "IN3")
		(16 "In7.Cu" signal "GND3")
		(18 "In8.Cu" signal "VCC")
		(20 "In9.Cu" signal "VCC1")
		(22 "In10.Cu" signal "GND4")
		(24 "In11.Cu" signal "IN4")
		(26 "In12.Cu" signal "GND5")
		(28 "In13.Cu" signal "IN5")
		(30 "In14.Cu" signal "GND6")
		(32 "In15.Cu" signal "IN6")
		(34 "In16.Cu" signal "GND7")
		(2 "B.Cu" signal "BOTTOM")
		(9 "F.Adhes" user "F.Adhesive")
		(11 "B.Adhes" user "B.Adhesive")
		(13 "F.Paste" user "Package Geometry/Pastemask Top")
		(15 "B.Paste" user "Package Geometry/Pastemask Bottom")
		(5 "F.SilkS" user "Ref Des/Silkscreen Top")
		(7 "B.SilkS" user "Ref Des/Silkscreen Bottom")
		(1 "F.Mask" user "Board Geometry/Soldermask Top")
		(3 "B.Mask" user "Board Geometry/Soldermask Bottom")
		(17 "Dwgs.User" user "User.Drawings")
		(19 "Cmts.User" user "User.Comments")
		(21 "Eco1.User" user "User.Eco1")
		(23 "Eco2.User" user "User.Eco2")
		(25 "Edge.Cuts" user "Board Geometry/Outline")
		(27 "Margin" user)
		(31 "F.CrtYd" user "Package Geometry/Place Bound Top")
		(29 "B.CrtYd" user "Package Geometry/Place Bound Bottom")
		(35 "F.Fab" user "Ref Des/Assembly Top")
		(33 "B.Fab" user "Ref Des/Assembly Bottom")
	)
	(footprint ""
		(layer "F.Cu")
		(at 140.208 -111.633 -90)
		(property "Reference" "U8009"
			(at 1.7018 -2.253488 90)
			(unlocked yes)
			(layer "F.SilkS")
			(effects
				(font
					(size 0.7874 0.5842)
					(thickness 0.1524)
				)
				(justify left)
			)
		)
		(property "Value" ""
			(at 0 0 270)
			(layer "F.Fab")
			(effects
				(font
					(size 1.27 1.27)
				)
			)
		)
		(duplicate_pad_numbers_are_jumpers no)
		(fp_line
			(start -1.868424 1.519936)
			(end 1.868424 1.519936)
			(stroke
				(width 0.1524)
				(type default)
			)
			(layer "F.SilkS")
		)
		(fp_line
			(start 1.868424 1.519936)
			(end 1.868424 -1.519936)
			(stroke
				(width 0.1524)
				(type default)
			)
			(layer "F.SilkS")
		)
		(fp_line
			(start -1.868424 -1.519936)
			(end -1.868424 1.519936)
			(stroke
				(width 0.1524)
				(type default)
			)
			(layer "F.SilkS")
		)
		(fp_line
			(start 1.868424 -1.519936)
			(end -1.868424 -1.519936)
			(stroke
				(width 0.1524)
				(type default)
			)
			(layer "F.SilkS")
		)
		(fp_line
			(start -0.700024 1.519936)
			(end 0.700024 1.519936)
			(stroke
				(width 0.1)
				(type default)
			)
			(layer "F.Fab")
		)
		(fp_line
			(start 0.700024 1.519936)
			(end 0.700024 -1.519936)
			(stroke
				(width 0.1)
				(type default)
			)
			(layer "F.Fab")
		)
		(fp_line
			(start -0.700024 -1.519936)
			(end -0.700024 1.519936)
			(stroke
				(width 0.1)
				(type default)
			)
			(layer "F.Fab")
		)
		(fp_line
			(start 0.700024 -1.519936)
			(end -0.700024 -1.519936)
			(stroke
				(width 0.1)
				(type default)
			)
			(layer "F.Fab")
		)
		(pad "1" smd rect
			(at -1.18491 -0.94996 180)
			(size 0.6096 1.0668)
			(layers "F.Cu" "F.Mask" "F.Paste")
			(net "UV_P2V5_COMP")
		)
		(pad "2" smd rect
			(at -1.18491 0.94996 180)
			(size 0.6096 1.0668)
			(layers "F.Cu" "F.Mask" "F.Paste")
			(net "GND")
		)
		(pad "3" smd rect
			(at 1.18491 0 180)
			(size 0.6096 1.0668)
			(layers "F.Cu" "F.Mask" "F.Paste")
			(net "Net_10849")
		)
	)
	(footprint ""
		(layer "F.Cu")
		(at 321.107308 -103.40975)
		(property "Reference" "R1308"
			(at 0 0 0)
			(layer "F.SilkS")
			(hide yes)
			(effects
				(font
					(size 1.27 1.27)
				)
			)
		)
		(property "Value" ""
			(at 0 0 0)
			(layer "F.Fab")
			(effects
				(font
					(size 1.27 1.27)
				)
			)
		)
		(duplicate_pad_numbers_are_jumpers no)
		(fp_line
			(start -0.7874 -0.4064)
			(end 0.7874 -0.4064)
			(stroke
				(width 0.1524)
				(type default)
			)
			(layer "F.SilkS")
		)
		(fp_line
			(start -0.7874 0.4064)
			(end -0.7874 -0.4064)
			(stroke
				(width 0.1524)
				(type default)
			)
			(layer "F.SilkS")
		)
		(fp_line
			(start 0.7874 -0.4064)
			(end 0.7874 0.4064)
			(stroke
				(width 0.1524)
				(type default)
			)
			(layer "F.SilkS")
		)
		(fp_line
			(start 0.7874 0.4064)
			(end -0.7874 0.4064)
			(stroke
				(width 0.1524)
				(type default)
			)
			(layer "F.SilkS")
		)
		(fp_line
			(start -0.67945 -0.305054)
			(end -0.12065 -0.305054)
			(stroke
				(width 0.1)
				(type default)
			)
			(layer "F.Fab")
		)
		(fp_line
			(start -0.67945 0.3048)
			(end -0.67945 -0.305054)
			(stroke
				(width 0.1)
				(type default)
			)
			(layer "F.Fab")
		)
		(fp_line
			(start -0.12065 -0.305054)
			(end -0.12065 -0.2794)
			(stroke
				(width 0.1)
				(type default)
			)
			(layer "F.Fab")
		)
		(fp_line
			(start -0.12065 -0.2794)
			(end 0.12065 -0.2794)
			(stroke
				(width 0.1)
				(type default)
			)
			(layer "F.Fab")
		)
		(fp_line
			(start -0.12065 0.2794)
			(end -0.12065 0.3048)
			(stroke
				(width 0.1)
				(type default)
			)
			(layer "F.Fab")
		)
		(fp_line
			(start -0.12065 0.3048)
			(end -0.67945 0.3048)
			(stroke
				(width 0.1)
				(type default)
			)
			(layer "F.Fab")
		)
		(fp_line
			(start 0.120396 0.2794)
			(end -0.12065 0.2794)
			(stroke
				(width 0.1)
				(type default)
			)
			(layer "F.Fab")
		)
		(fp_line
			(start 0.120396 0.3048)
			(end 0.120396 0.2794)
			(stroke
				(width 0.1)
				(type default)
			)
			(layer "F.Fab")
		)
		(fp_line
			(start 0.12065 -0.3048)
			(end 0.67945 -0.3048)
			(stroke
				(width 0.1)
				(type default)
			)
			(layer "F.Fab")
		)
		(fp_line
			(start 0.12065 -0.2794)
			(end 0.12065 -0.3048)
			(stroke
				(width 0.1)
				(type default)
			)
			(layer "F.Fab")
		)
		(fp_line
			(start 0.67945 -0.3048)
			(end 0.67945 0.3048)
			(stroke
				(width 0.1)
				(type default)
			)
			(layer "F.Fab")
		)
		(fp_line
			(start 0.67945 0.3048)
			(end 0.120396 0.3048)
			(stroke
				(width 0.1)
				(type default)
			)
			(layer "F.Fab")
		)
		(pad "1" smd circle
			(at -0.40005 0)
			(size 0 0)
			(layers "F.Cu" "F.Mask" "F.Paste")
			(net "GND")
		)
		(pad "2" smd circle
			(at 0.40005 0)
			(size 0 0)
			(layers "F.Cu" "F.Mask" "F.Paste")
			(net "INA230_8_A0")
		)
	)
	(footprint ""
		(layer "F.Cu")
		(at 430.155858 -430.891188)
		(property "Reference" "C6087"
			(at 0 0 0)
			(layer "F.SilkS")
			(hide yes)
			(effects
				(font
					(size 1.27 1.27)
				)
			)
		)
		(property "Value" ""
			(at 0 0 0)
			(layer "F.Fab")
			(effects
				(font
					(size 1.27 1.27)
				)
			)
		)
		(duplicate_pad_numbers_are_jumpers no)
		(fp_line
			(start -0.7874 -0.4064)
			(end 0.7874 -0.4064)
			(stroke
				(width 0.1524)
				(type default)
			)
			(layer "F.SilkS")
		)
		(fp_line
			(start -0.7874 0.4064)
			(end -0.7874 -0.4064)
			(stroke
				(width 0.1524)
				(type default)
			)
			(layer "F.SilkS")
		)
		(fp_line
			(start 0.7874 -0.4064)
			(end 0.7874 0.4064)
			(stroke
				(width 0.1524)
				(type default)
			)
			(layer "F.SilkS")
		)
		(fp_line
			(start 0.7874 0.4064)
			(end -0.7874 0.4064)
			(stroke
				(width 0.1524)
				(type default)
			)
			(layer "F.SilkS")
		)
		(fp_line
			(start -0.67945 -0.305054)
			(end -0.12065 -0.305054)
			(stroke
				(width 0.1)
				(type default)
			)
			(layer "F.Fab")
		)
		(fp_line
			(start -0.67945 0.3048)
			(end -0.67945 -0.305054)
			(stroke
				(width 0.1)
				(type default)
			)
			(layer "F.Fab")
		)
		(fp_line
			(start -0.12065 -0.305054)
			(end -0.12065 -0.2794)
			(stroke
				(width 0.1)
				(type default)
			)
			(layer "F.Fab")
		)
		(fp_line
			(start -0.12065 -0.2794)
			(end 0.12065 -0.2794)
			(stroke
				(width 0.1)
				(type default)
			)
			(layer "F.Fab")
		)
		(fp_line
			(start -0.12065 0.2794)
			(end -0.12065 0.3048)
			(stroke
				(width 0.1)
				(type default)
			)
			(layer "F.Fab")
		)
		(fp_line
			(start -0.12065 0.3048)
			(end -0.67945 0.3048)
			(stroke
				(width 0.1)
				(type default)
			)
			(layer "F.Fab")
		)
		(fp_line
			(start 0.120396 0.2794)
			(end -0.12065 0.2794)
			(stroke
				(width 0.1)
				(type default)
			)
			(layer "F.Fab")
		)
		(fp_line
			(start 0.120396 0.3048)
			(end 0.120396 0.2794)
			(stroke
				(width 0.1)
				(type default)
			)
			(layer "F.Fab")
		)
		(fp_line
			(start 0.12065 -0.3048)
			(end 0.67945 -0.3048)
			(stroke
				(width 0.1)
				(type default)
			)
			(layer "F.Fab")
		)
		(fp_line
			(start 0.12065 -0.2794)
			(end 0.12065 -0.3048)
			(stroke
				(width 0.1)
				(type default)
			)
			(layer "F.Fab")
		)
		(fp_line
			(start 0.67945 -0.3048)
			(end 0.67945 0.3048)
			(stroke
				(width 0.1)
				(type default)
			)
			(layer "F.Fab")
		)
		(fp_line
			(start 0.67945 0.3048)
			(end 0.120396 0.3048)
			(stroke
				(width 0.1)
				(type default)
			)
			(layer "F.Fab")
		)
		(pad "1" smd circle
			(at -0.40005 0)
			(size 0 0)
			(layers "F.Cu" "F.Mask" "F.Paste")
			(net "P3V3_AUX")
		)
		(pad "2" smd circle
			(at 0.40005 0)
			(size 0 0)
			(layers "F.Cu" "F.Mask" "F.Paste")
			(net "GND")
		)
	)
)
